(kicad_pcb
	(version 20260206)
	(generator "pcbnew")
	(generator_version "10.0")
	(general
		(thickness 1.6)
		(legacy_teardrops no)
	)
	(paper "A4")
	(title_block
		(title "03242023_DA0F0TMBIJ0_F0T_Motherboard_J_brd_V01_OCP.brd")
		(comment 1 "Grand Teton / footprints 3165-3170 of 6105")
	)
	(layers
		(0 "F.Cu" signal "TOP")
		(4 "In1.Cu" signal "GND")
		(6 "In2.Cu" signal "IN1")
		(8 "In3.Cu" signal "GND1")
		(10 "In4.Cu" signal "IN2")
		(12 "In5.Cu" signal "GND2")
		(14 "In6.Cu" signal "IN3")
		(16 "In7.Cu" signal "GND3")
		(18 "In8.Cu" signal "VCC")
		(20 "In9.Cu" signal "VCC1")
		(22 "In10.Cu" signal "GND4")
		(24 "In11.Cu" signal "IN4")
		(26 "In12.Cu" signal "GND5")
		(28 "In13.Cu" signal "IN5")
		(30 "In14.Cu" signal "GND6")
		(32 "In15.Cu" signal "IN6")
		(34 "In16.Cu" signal "GND7")
		(2 "B.Cu" signal "BOTTOM")
		(9 "F.Adhes" user "F.Adhesive")
		(11 "B.Adhes" user "B.Adhesive")
		(13 "F.Paste" user "Package Geometry/Pastemask Top")
		(15 "B.Paste" user "Package Geometry/Pastemask Bottom")
		(5 "F.SilkS" user "Ref Des/Silkscreen Top")
		(7 "B.SilkS" user "Ref Des/Silkscreen Bottom")
		(1 "F.Mask" user "Board Geometry/Soldermask Top")
		(3 "B.Mask" user "Board Geometry/Soldermask Bottom")
		(17 "Dwgs.User" user "User.Drawings")
		(19 "Cmts.User" user "User.Comments")
		(21 "Eco1.User" user "User.Eco1")
		(23 "Eco2.User" user "User.Eco2")
		(25 "Edge.Cuts" user "Board Geometry/Outline")
		(27 "Margin" user)
		(31 "F.CrtYd" user "Package Geometry/Place Bound Top")
		(29 "B.CrtYd" user "Package Geometry/Place Bound Bottom")
		(35 "F.Fab" user "Ref Des/Assembly Top")
		(33 "B.Fab" user "Ref Des/Assembly Bottom")
	)
	(footprint ""
		(layer "F.Cu")
		(at 320.8401 -76.585064 90)
		(property "Reference" "R2235"
			(at 0 0 90)
			(layer "F.SilkS")
			(hide yes)
			(effects
				(font
					(size 1.27 1.27)
				)
			)
		)
		(property "Value" ""
			(at 0 0 90)
			(layer "F.Fab")
			(effects
				(font
					(size 1.27 1.27)
				)
			)
		)
		(duplicate_pad_numbers_are_jumpers no)
		(fp_line
			(start 0.7874 -0.4064)
			(end 0.7874 0.4064)
			(stroke
				(width 0.1524)
				(type default)
			)
			(layer "F.SilkS")
		)
		(fp_line
			(start -0.7874 -0.4064)
			(end 0.7874 -0.4064)
			(stroke
				(width 0.1524)
				(type default)
			)
			(layer "F.SilkS")
		)
		(fp_line
			(start 0.7874 0.4064)
			(end -0.7874 0.4064)
			(stroke
				(width 0.1524)
				(type default)
			)
			(layer "F.SilkS")
		)
		(fp_line
			(start -0.7874 0.4064)
			(end -0.7874 -0.4064)
			(stroke
				(width 0.1524)
				(type default)
			)
			(layer "F.SilkS")
		)
		(fp_line
			(start -0.12065 -0.305054)
			(end -0.12065 -0.2794)
			(stroke
				(width 0.1)
				(type default)
			)
			(layer "F.Fab")
		)
		(fp_line
			(start -0.67945 -0.305054)
			(end -0.12065 -0.305054)
			(stroke
				(width 0.1)
				(type default)
			)
			(layer "F.Fab")
		)
		(fp_line
			(start 0.67945 -0.3048)
			(end 0.67945 0.3048)
			(stroke
				(width 0.1)
				(type default)
			)
			(layer "F.Fab")
		)
		(fp_line
			(start 0.12065 -0.3048)
			(end 0.67945 -0.3048)
			(stroke
				(width 0.1)
				(type default)
			)
			(layer "F.Fab")
		)
		(fp_line
			(start 0.12065 -0.2794)
			(end 0.12065 -0.3048)
			(stroke
				(width 0.1)
				(type default)
			)
			(layer "F.Fab")
		)
		(fp_line
			(start -0.12065 -0.2794)
			(end 0.12065 -0.2794)
			(stroke
				(width 0.1)
				(type default)
			)
			(layer "F.Fab")
		)
		(fp_line
			(start 0.120396 0.2794)
			(end -0.12065 0.2794)
			(stroke
				(width 0.1)
				(type default)
			)
			(layer "F.Fab")
		)
		(fp_line
			(start -0.12065 0.2794)
			(end -0.12065 0.3048)
			(stroke
				(width 0.1)
				(type default)
			)
			(layer "F.Fab")
		)
		(fp_line
			(start 0.67945 0.3048)
			(end 0.120396 0.3048)
			(stroke
				(width 0.1)
				(type default)
			)
			(layer "F.Fab")
		)
		(fp_line
			(start 0.120396 0.3048)
			(end 0.120396 0.2794)
			(stroke
				(width 0.1)
				(type default)
			)
			(layer "F.Fab")
		)
		(fp_line
			(start -0.12065 0.3048)
			(end -0.67945 0.3048)
			(stroke
				(width 0.1)
				(type default)
			)
			(layer "F.Fab")
		)
		(fp_line
			(start -0.67945 0.3048)
			(end -0.67945 -0.305054)
			(stroke
				(width 0.1)
				(type default)
			)
			(layer "F.Fab")
		)
		(pad "1" smd circle
			(at -0.40005 0 90)
			(size 0 0)
			(layers "F.Cu" "F.Mask" "F.Paste")
			(net "FM_BOARD_SKU_ID4")
		)
		(pad "2" smd circle
			(at 0.40005 0 90)
			(size 0 0)
			(layers "F.Cu" "F.Mask" "F.Paste")
			(net "GND")
		)
	)
	(footprint ""
		(layer "F.Cu")
		(at 369.369848 -358.430576)
		(property "Reference" "PC1251"
			(at 0 0 0)
			(layer "F.SilkS")
			(hide yes)
			(effects
				(font
					(size 1.27 1.27)
				)
			)
		)
		(property "Value" ""
			(at 0 0 0)
			(layer "F.Fab")
			(effects
				(font
					(size 1.27 1.27)
				)
			)
		)
		(duplicate_pad_numbers_are_jumpers no)
		(fp_line
			(start -0.7874 -0.4064)
			(end 0.7874 -0.4064)
			(stroke
				(width 0.1524)
				(type default)
			)
			(layer "F.SilkS")
		)
		(fp_line
			(start -0.7874 0.4064)
			(end -0.7874 -0.4064)
			(stroke
				(width 0.1524)
				(type default)
			)
			(layer "F.SilkS")
		)
		(fp_line
			(start 0.7874 -0.4064)
			(end 0.7874 0.4064)
			(stroke
				(width 0.1524)
				(type default)
			)
			(layer "F.SilkS")
		)
		(fp_line
			(start 0.7874 0.4064)
			(end -0.7874 0.4064)
			(stroke
				(width 0.1524)
				(type default)
			)
			(layer "F.SilkS")
		)
		(fp_line
			(start -0.67945 -0.305054)
			(end -0.12065 -0.305054)
			(stroke
				(width 0.1)
				(type default)
			)
			(layer "F.Fab")
		)
		(fp_line
			(start -0.67945 0.3048)
			(end -0.67945 -0.305054)
			(stroke
				(width 0.1)
				(type default)
			)
			(layer "F.Fab")
		)
		(fp_line
			(start -0.12065 -0.305054)
			(end -0.12065 -0.2794)
			(stroke
				(width 0.1)
				(type default)
			)
			(layer "F.Fab")
		)
		(fp_line
			(start -0.12065 -0.2794)
			(end 0.12065 -0.2794)
			(stroke
				(width 0.1)
				(type default)
			)
			(layer "F.Fab")
		)
		(fp_line
			(start -0.12065 0.2794)
			(end -0.12065 0.3048)
			(stroke
				(width 0.1)
				(type default)
			)
			(layer "F.Fab")
		)
		(fp_line
			(start -0.12065 0.3048)
			(end -0.67945 0.3048)
			(stroke
				(width 0.1)
				(type default)
			)
			(layer "F.Fab")
		)
		(fp_line
			(start 0.120396 0.2794)
			(end -0.12065 0.2794)
			(stroke
				(width 0.1)
				(type default)
			)
			(layer "F.Fab")
		)
		(fp_line
			(start 0.120396 0.3048)
			(end 0.120396 0.2794)
			(stroke
				(width 0.1)
				(type default)
			)
			(layer "F.Fab")
		)
		(fp_line
			(start 0.12065 -0.3048)
			(end 0.67945 -0.3048)
			(stroke
				(width 0.1)
				(type default)
			)
			(layer "F.Fab")
		)
		(fp_line
			(start 0.12065 -0.2794)
			(end 0.12065 -0.3048)
			(stroke
				(width 0.1)
				(type default)
			)
			(layer "F.Fab")
		)
		(fp_line
			(start 0.67945 -0.3048)
			(end 0.67945 0.3048)
			(stroke
				(width 0.1)
				(type default)
			)
			(layer "F.Fab")
		)
		(fp_line
			(start 0.67945 0.3048)
			(end 0.120396 0.3048)
			(stroke
				(width 0.1)
				(type default)
			)
			(layer "F.Fab")
		)
		(pad "1" smd circle
			(at -0.40005 0)
			(size 0 0)
			(layers "F.Cu" "F.Mask" "F.Paste")
			(net "PVPP_HBM_CPU0_REF")
		)
		(pad "2" smd circle
			(at 0.40005 0)
			(size 0 0)
			(layers "F.Cu" "F.Mask" "F.Paste")
			(net "SH_PVPP_HBM_CPU0_N")
		)
	)
	(footprint ""
		(layer "F.Cu")
		(at 140.70838 -32.458152 180)
		(property "Reference" "R3307"
			(at 0 0 180)
			(layer "F.SilkS")
			(hide yes)
			(effects
				(font
					(size 1.27 1.27)
				)
			)
		)
		(property "Value" ""
			(at 0 0 180)
			(layer "F.Fab")
			(effects
				(font
					(size 1.27 1.27)
				)
			)
		)
		(duplicate_pad_numbers_are_jumpers no)
		(fp_line
			(start 0.7874 0.4064)
			(end -0.7874 0.4064)
			(stroke
				(width 0.1524)
				(type default)
			)
			(layer "F.SilkS")
		)
		(fp_line
			(start 0.7874 -0.4064)
			(end 0.7874 0.4064)
			(stroke
				(width 0.1524)
				(type default)
			)
			(layer "F.SilkS")
		)
		(fp_line
			(start -0.7874 0.4064)
			(end -0.7874 -0.4064)
			(stroke
				(width 0.1524)
				(type default)
			)
			(layer "F.SilkS")
		)
		(fp_line
			(start -0.7874 -0.4064)
			(end 0.7874 -0.4064)
			(stroke
				(width 0.1524)
				(type default)
			)
			(layer "F.SilkS")
		)
		(fp_line
			(start 0.67945 0.3048)
			(end 0.120396 0.3048)
			(stroke
				(width 0.1)
				(type default)
			)
			(layer "F.Fab")
		)
		(fp_line
			(start 0.67945 -0.3048)
			(end 0.67945 0.3048)
			(stroke
				(width 0.1)
				(type default)
			)
			(layer "F.Fab")
		)
		(fp_line
			(start 0.12065 -0.2794)
			(end 0.12065 -0.3048)
			(stroke
				(width 0.1)
				(type default)
			)
			(layer "F.Fab")
		)
		(fp_line
			(start 0.12065 -0.3048)
			(end 0.67945 -0.3048)
			(stroke
				(width 0.1)
				(type default)
			)
			(layer "F.Fab")
		)
		(fp_line
			(start 0.120396 0.3048)
			(end 0.120396 0.2794)
			(stroke
				(width 0.1)
				(type default)
			)
			(layer "F.Fab")
		)
		(fp_line
			(start 0.120396 0.2794)
			(end -0.12065 0.2794)
			(stroke
				(width 0.1)
				(type default)
			)
			(layer "F.Fab")
		)
		(fp_line
			(start -0.12065 0.3048)
			(end -0.67945 0.3048)
			(stroke
				(width 0.1)
				(type default)
			)
			(layer "F.Fab")
		)
		(fp_line
			(start -0.12065 0.2794)
			(end -0.12065 0.3048)
			(stroke
				(width 0.1)
				(type default)
			)
			(layer "F.Fab")
		)
		(fp_line
			(start -0.12065 -0.2794)
			(end 0.12065 -0.2794)
			(stroke
				(width 0.1)
				(type default)
			)
			(layer "F.Fab")
		)
		(fp_line
			(start -0.12065 -0.305054)
			(end -0.12065 -0.2794)
			(stroke
				(width 0.1)
				(type default)
			)
			(layer "F.Fab")
		)
		(fp_line
			(start -0.67945 0.3048)
			(end -0.67945 -0.305054)
			(stroke
				(width 0.1)
				(type default)
			)
			(layer "F.Fab")
		)
		(fp_line
			(start -0.67945 -0.305054)
			(end -0.12065 -0.305054)
			(stroke
				(width 0.1)
				(type default)
			)
			(layer "F.Fab")
		)
		(pad "1" smd circle
			(at -0.40005 0 180)
			(size 0 0)
			(layers "F.Cu" "F.Mask" "F.Paste")
			(net "OCP_SFF_RBT_ARB_IN_MUX2")
		)
		(pad "2" smd circle
			(at 0.40005 0 180)
			(size 0 0)
			(layers "F.Cu" "F.Mask" "F.Paste")
			(net "OCP_SFF_RBT_ARB_IN_MUX2_R")
		)
	)
	(footprint ""
		(layer "F.Cu")
		(at 49.755552 -163.822634 90)
		(property "Reference" "PR1746"
			(at 0 0 90)
			(layer "F.SilkS")
			(hide yes)
			(effects
				(font
					(size 1.27 1.27)
				)
			)
		)
		(property "Value" ""
			(at 0 0 90)
			(layer "F.Fab")
			(effects
				(font
					(size 1.27 1.27)
				)
			)
		)
		(duplicate_pad_numbers_are_jumpers no)
		(fp_line
			(start 0.7874 -0.4064)
			(end 0.7874 0.4064)
			(stroke
				(width 0.1524)
				(type default)
			)
			(layer "F.SilkS")
		)
		(fp_line
			(start -0.7874 -0.4064)
			(end 0.7874 -0.4064)
			(stroke
				(width 0.1524)
				(type default)
			)
			(layer "F.SilkS")
		)
		(fp_line
			(start 0.7874 0.4064)
			(end -0.7874 0.4064)
			(stroke
				(width 0.1524)
				(type default)
			)
			(layer "F.SilkS")
		)
		(fp_line
			(start -0.7874 0.4064)
			(end -0.7874 -0.4064)
			(stroke
				(width 0.1524)
				(type default)
			)
			(layer "F.SilkS")
		)
		(fp_line
			(start -0.12065 -0.305054)
			(end -0.12065 -0.2794)
			(stroke
				(width 0.1)
				(type default)
			)
			(layer "F.Fab")
		)
		(fp_line
			(start -0.67945 -0.305054)
			(end -0.12065 -0.305054)
			(stroke
				(width 0.1)
				(type default)
			)
			(layer "F.Fab")
		)
		(fp_line
			(start 0.67945 -0.3048)
			(end 0.67945 0.3048)
			(stroke
				(width 0.1)
				(type default)
			)
			(layer "F.Fab")
		)
		(fp_line
			(start 0.12065 -0.3048)
			(end 0.67945 -0.3048)
			(stroke
				(width 0.1)
				(type default)
			)
			(layer "F.Fab")
		)
		(fp_line
			(start 0.12065 -0.2794)
			(end 0.12065 -0.3048)
			(stroke
				(width 0.1)
				(type default)
			)
			(layer "F.Fab")
		)
		(fp_line
			(start -0.12065 -0.2794)
			(end 0.12065 -0.2794)
			(stroke
				(width 0.1)
				(type default)
			)
			(layer "F.Fab")
		)
		(fp_line
			(start 0.120396 0.2794)
			(end -0.12065 0.2794)
			(stroke
				(width 0.1)
				(type default)
			)
			(layer "F.Fab")
		)
		(fp_line
			(start -0.12065 0.2794)
			(end -0.12065 0.3048)
			(stroke
				(width 0.1)
				(type default)
			)
			(layer "F.Fab")
		)
		(fp_line
			(start 0.67945 0.3048)
			(end 0.120396 0.3048)
			(stroke
				(width 0.1)
				(type default)
			)
			(layer "F.Fab")
		)
		(fp_line
			(start 0.120396 0.3048)
			(end 0.120396 0.2794)
			(stroke
				(width 0.1)
				(type default)
			)
			(layer "F.Fab")
		)
		(fp_line
			(start -0.12065 0.3048)
			(end -0.67945 0.3048)
			(stroke
				(width 0.1)
				(type default)
			)
			(layer "F.Fab")
		)
		(fp_line
			(start -0.67945 0.3048)
			(end -0.67945 -0.305054)
			(stroke
				(width 0.1)
				(type default)
			)
			(layer "F.Fab")
		)
		(pad "1" smd circle
			(at -0.40005 0 90)
			(size 0 0)
			(layers "F.Cu" "F.Mask" "F.Paste")
			(net "PVCCD_HV_CPU1_LSET1")
		)
		(pad "2" smd circle
			(at 0.40005 0 90)
			(size 0 0)
			(layers "F.Cu" "F.Mask" "F.Paste")
			(net "GND")
		)
	)
	(footprint ""
		(layer "F.Cu")
		(at 150.67788 -45.938948 90)
		(property "Reference" "R3595"
			(at 0 0 90)
			(layer "F.SilkS")
			(hide yes)
			(effects
				(font
					(size 1.27 1.27)
				)
			)
		)
		(property "Value" ""
			(at 0 0 90)
			(layer "F.Fab")
			(effects
				(font
					(size 1.27 1.27)
				)
			)
		)
		(duplicate_pad_numbers_are_jumpers no)
		(fp_line
			(start 0.7874 -0.4064)
			(end 0.7874 0.4064)
			(stroke
				(width 0.1524)
				(type default)
			)
			(layer "F.SilkS")
		)
		(fp_line
			(start -0.7874 -0.4064)
			(end 0.7874 -0.4064)
			(stroke
				(width 0.1524)
				(type default)
			)
			(layer "F.SilkS")
		)
		(fp_line
			(start 0.7874 0.4064)
			(end -0.7874 0.4064)
			(stroke
				(width 0.1524)
				(type default)
			)
			(layer "F.SilkS")
		)
		(fp_line
			(start -0.7874 0.4064)
			(end -0.7874 -0.4064)
			(stroke
				(width 0.1524)
				(type default)
			)
			(layer "F.SilkS")
		)
		(fp_line
			(start -0.12065 -0.305054)
			(end -0.12065 -0.2794)
			(stroke
				(width 0.1)
				(type default)
			)
			(layer "F.Fab")
		)
		(fp_line
			(start -0.67945 -0.305054)
			(end -0.12065 -0.305054)
			(stroke
				(width 0.1)
				(type default)
			)
			(layer "F.Fab")
		)
		(fp_line
			(start 0.67945 -0.3048)
			(end 0.67945 0.3048)
			(stroke
				(width 0.1)
				(type default)
			)
			(layer "F.Fab")
		)
		(fp_line
			(start 0.12065 -0.3048)
			(end 0.67945 -0.3048)
			(stroke
				(width 0.1)
				(type default)
			)
			(layer "F.Fab")
		)
		(fp_line
			(start 0.12065 -0.2794)
			(end 0.12065 -0.3048)
			(stroke
				(width 0.1)
				(type default)
			)
			(layer "F.Fab")
		)
		(fp_line
			(start -0.12065 -0.2794)
			(end 0.12065 -0.2794)
			(stroke
				(width 0.1)
				(type default)
			)
			(layer "F.Fab")
		)
		(fp_line
			(start 0.120396 0.2794)
			(end -0.12065 0.2794)
			(stroke
				(width 0.1)
				(type default)
			)
			(layer "F.Fab")
		)
		(fp_line
			(start -0.12065 0.2794)
			(end -0.12065 0.3048)
			(stroke
				(width 0.1)
				(type default)
			)
			(layer "F.Fab")
		)
		(fp_line
			(start 0.67945 0.3048)
			(end 0.120396 0.3048)
			(stroke
				(width 0.1)
				(type default)
			)
			(layer "F.Fab")
		)
		(fp_line
			(start 0.120396 0.3048)
			(end 0.120396 0.2794)
			(stroke
				(width 0.1)
				(type default)
			)
			(layer "F.Fab")
		)
		(fp_line
			(start -0.12065 0.3048)
			(end -0.67945 0.3048)
			(stroke
				(width 0.1)
				(type default)
			)
			(layer "F.Fab")
		)
		(fp_line
			(start -0.67945 0.3048)
			(end -0.67945 -0.305054)
			(stroke
				(width 0.1)
				(type default)
			)
			(layer "F.Fab")
		)
		(pad "1" smd circle
			(at -0.40005 0 90)
			(size 0 0)
			(layers "F.Cu" "F.Mask" "F.Paste")
			(net "SMB_INA230_3V3AUX_SDA")
		)
		(pad "2" smd circle
			(at 0.40005 0 90)
			(size 0 0)
			(layers "F.Cu" "F.Mask" "F.Paste")
			(net "SMB_INA230_4_3V3AUX_SDA_R")
		)
	)
	(footprint ""
		(layer "F.Cu")
		(at 31.29788 -425.287948)
		(property "Reference" "R3391"
			(at 0 0 0)
			(layer "F.SilkS")
			(hide yes)
			(effects
				(font
					(size 1.27 1.27)
				)
			)
		)
		(property "Value" ""
			(at 0 0 0)
			(layer "F.Fab")
			(effects
				(font
					(size 1.27 1.27)
				)
			)
		)
		(duplicate_pad_numbers_are_jumpers no)
		(fp_line
			(start -0.7874 -0.4064)
			(end 0.7874 -0.4064)
			(stroke
				(width 0.1524)
				(type default)
			)
			(layer "F.SilkS")
		)
		(fp_line
			(start -0.7874 0.4064)
			(end -0.7874 -0.4064)
			(stroke
				(width 0.1524)
				(type default)
			)
			(layer "F.SilkS")
		)
		(fp_line
			(start 0.7874 -0.4064)
			(end 0.7874 0.4064)
			(stroke
				(width 0.1524)
				(type default)
			)
			(layer "F.SilkS")
		)
		(fp_line
			(start 0.7874 0.4064)
			(end -0.7874 0.4064)
			(stroke
				(width 0.1524)
				(type default)
			)
			(layer "F.SilkS")
		)
		(fp_line
			(start -0.67945 -0.305054)
			(end -0.12065 -0.305054)
			(stroke
				(width 0.1)
				(type default)
			)
			(layer "F.Fab")
		)
		(fp_line
			(start -0.67945 0.3048)
			(end -0.67945 -0.305054)
			(stroke
				(width 0.1)
				(type default)
			)
			(layer "F.Fab")
		)
		(fp_line
			(start -0.12065 -0.305054)
			(end -0.12065 -0.2794)
			(stroke
				(width 0.1)
				(type default)
			)
			(layer "F.Fab")
		)
		(fp_line
			(start -0.12065 -0.2794)
			(end 0.12065 -0.2794)
			(stroke
				(width 0.1)
				(type default)
			)
			(layer "F.Fab")
		)
		(fp_line
			(start -0.12065 0.2794)
			(end -0.12065 0.3048)
			(stroke
				(width 0.1)
				(type default)
			)
			(layer "F.Fab")
		)
		(fp_line
			(start -0.12065 0.3048)
			(end -0.67945 0.3048)
			(stroke
				(width 0.1)
				(type default)
			)
			(layer "F.Fab")
		)
		(fp_line
			(start 0.120396 0.2794)
			(end -0.12065 0.2794)
			(stroke
				(width 0.1)
				(type default)
			)
			(layer "F.Fab")
		)
		(fp_line
			(start 0.120396 0.3048)
			(end 0.120396 0.2794)
			(stroke
				(width 0.1)
				(type default)
			)
			(layer "F.Fab")
		)
		(fp_line
			(start 0.12065 -0.3048)
			(end 0.67945 -0.3048)
			(stroke
				(width 0.1)
				(type default)
			)
			(layer "F.Fab")
		)
		(fp_line
			(start 0.12065 -0.2794)
			(end 0.12065 -0.3048)
			(stroke
				(width 0.1)
				(type default)
			)
			(layer "F.Fab")
		)
		(fp_line
			(start 0.67945 -0.3048)
			(end 0.67945 0.3048)
			(stroke
				(width 0.1)
				(type default)
			)
			(layer "F.Fab")
		)
		(fp_line
			(start 0.67945 0.3048)
			(end 0.120396 0.3048)
			(stroke
				(width 0.1)
				(type default)
			)
			(layer "F.Fab")
		)
		(pad "1" smd circle
			(at -0.40005 0)
			(size 0 0)
			(layers "F.Cu" "F.Mask" "F.Paste")
			(net "RST_PERST_1_SWB_BUF_R_N")
		)
		(pad "2" smd circle
			(at 0.40005 0)
			(size 0 0)
			(layers "F.Cu" "F.Mask" "F.Paste")
			(net "RST_PERST_1_SWB_BUF_N")
		)
	)
)
